(kicad_pcb
	(version 20260206)
	(generator "pcbnew")
	(generator_version "10.0")
	(general
		(thickness 1.6)
		(legacy_teardrops no)
	)
	(paper "A4")
	(title_block
		(title "01162023_DA0F0TEBIF0_F0T_Expander_BD_F_brd_V02_OCP.brd")
		(comment 1 "Grand Teton / footprint 1840 of 9728 (U6), pads 441-484 of 484")
	)
	(layers
		(0 "F.Cu" signal "TOP")
		(4 "In1.Cu" signal "GND")
		(6 "In2.Cu" signal "VCC")
		(8 "In3.Cu" signal "VCC1")
		(10 "In4.Cu" signal "GND1")
		(12 "In5.Cu" signal "IN1")
		(14 "In6.Cu" signal "GND2")
		(16 "In7.Cu" signal "IN2")
		(18 "In8.Cu" signal "GND3")
		(20 "In9.Cu" signal "IN3")
		(22 "In10.Cu" signal "GND4")
		(24 "In11.Cu" signal "IN4")
		(26 "In12.Cu" signal "GND5")
		(28 "In13.Cu" signal "IN5")
		(30 "In14.Cu" signal "GND6")
		(32 "In15.Cu" signal "IN6")
		(34 "In16.Cu" signal "GND7")
		(2 "B.Cu" signal "BOTTOM")
		(9 "F.Adhes" user "F.Adhesive")
		(11 "B.Adhes" user "B.Adhesive")
		(13 "F.Paste" user "Package Geometry/Pastemask Top")
		(15 "B.Paste" user "Package Geometry/Pastemask Bottom")
		(5 "F.SilkS" user "Ref Des/Silkscreen Top")
		(7 "B.SilkS" user "Ref Des/Silkscreen Bottom")
		(1 "F.Mask" user "Board Geometry/Soldermask Top")
		(3 "B.Mask" user "Board Geometry/Soldermask Bottom")
		(17 "Dwgs.User" user "User.Drawings")
		(19 "Cmts.User" user "User.Comments")
		(21 "Eco1.User" user "User.Eco1")
		(23 "Eco2.User" user "User.Eco2")
		(25 "Edge.Cuts" user "Board Geometry/Outline")
		(27 "Margin" user)
		(31 "F.CrtYd" user "Package Geometry/Place Bound Top")
		(29 "B.CrtYd" user "Package Geometry/Place Bound Bottom")
		(35 "F.Fab" user "Ref Des/Assembly Top")
		(33 "B.Fab" user "Ref Des/Assembly Bottom")
	)
	(footprint ""
		(layer "F.Cu")
		(at 342.493854 -219.587064)
		(property "Reference" "U6"
			(at -10.3632 -10.963148 0)
			(unlocked yes)
			(layer "F.SilkS")
			(effects
				(font
					(size 0.7874 0.5842)
					(thickness 0.1524)
				)
				(justify left)
			)
		)
		(property "Value" ""
			(at 0 0 0)
			(layer "F.Fab")
			(effects
				(font
					(size 1.27 1.27)
				)
			)
		)
		(duplicate_pad_numbers_are_jumpers no)
		(pad "W1" smd circle
			(at -8.400034 5.999988)
			(size 0.4064 0.4064)
			(layers "F.Cu" "F.Mask" "F.Paste")
			(net "SSD13_PEX_PWR_EN_R")
		)
		(pad "W2" smd circle
			(at -7.599934 5.999988)
			(size 0.4064 0.4064)
			(layers "F.Cu" "F.Mask" "F.Paste")
			(net "PRSNT_SSD13_FPGA_N")
		)
		(pad "W3" smd circle
			(at -6.800088 5.999988)
			(size 0.4064 0.4064)
			(layers "F.Cu" "F.Mask" "F.Paste")
			(net "PRSNT_SSD12_FPGA_N")
		)
		(pad "W4" smd circle
			(at -5.999988 5.999988)
			(size 0.4064 0.4064)
			(layers "F.Cu" "F.Mask" "F.Paste")
			(net "RST_PEX_SSD11_PERST_R_N")
		)
		(pad "W5" smd circle
			(at -5.199888 5.999988)
			(size 0.4064 0.4064)
			(layers "F.Cu" "F.Mask" "F.Paste")
			(net "PRSNT_SSD9_R_N")
		)
		(pad "W6" smd circle
			(at -4.400042 5.999988)
			(size 0.4064 0.4064)
			(layers "F.Cu" "F.Mask" "F.Paste")
			(net "SSD10_PWRDIS")
		)
		(pad "W7" smd circle
			(at -3.599942 5.999988)
			(size 0.4064 0.4064)
			(layers "F.Cu" "F.Mask" "F.Paste")
			(net "P3V3_FPGA_VCCIO2")
		)
		(pad "W8" smd circle
			(at -2.800096 5.999988)
			(size 0.4064 0.4064)
			(layers "F.Cu" "F.Mask" "F.Paste")
			(net "SSD11_CLK_EN_N")
		)
		(pad "W9" smd circle
			(at -1.999996 5.999988)
			(size 0.4064 0.4064)
			(layers "F.Cu" "F.Mask" "F.Paste")
			(net "SSD12_PWR_EN")
		)
		(pad "W10" smd circle
			(at -1.199896 5.999988)
			(size 0.4064 0.4064)
			(layers "F.Cu" "F.Mask" "F.Paste")
			(net "PWRGD_P3V3_SSD13_R")
		)
		(pad "W11" smd circle
			(at -0.40005 5.999988)
			(size 0.4064 0.4064)
			(layers "F.Cu" "F.Mask" "F.Paste")
			(net "P3V3_FPGA_VCCIO2")
		)
		(pad "W12" smd circle
			(at 0.40005 5.999988)
			(size 0.4064 0.4064)
			(layers "F.Cu" "F.Mask" "F.Paste")
			(net "GND")
		)
		(pad "W13" smd circle
			(at 1.199896 5.999988)
			(size 0.4064 0.4064)
			(layers "F.Cu" "F.Mask" "F.Paste")
			(net "PRSNT_SSD0_FPGA_N")
		)
		(pad "W14" smd circle
			(at 1.999996 5.999988)
			(size 0.4064 0.4064)
			(layers "F.Cu" "F.Mask" "F.Paste")
			(net "SSD1_PWRDIS_BIC_R")
		)
		(pad "W15" smd circle
			(at 2.800096 5.999988)
			(size 0.4064 0.4064)
			(layers "F.Cu" "F.Mask" "F.Paste")
			(net "RST_PEX_SSD2_PERST_R_N")
		)
		(pad "W16" smd circle
			(at 3.599942 5.999988)
			(size 0.4064 0.4064)
			(layers "F.Cu" "F.Mask" "F.Paste")
			(net "P3V3_FPGA_VCCIO2")
		)
		(pad "W17" smd circle
			(at 4.400042 5.999988)
			(size 0.4064 0.4064)
			(layers "F.Cu" "F.Mask" "F.Paste")
			(net "FPGA_PEX2_MODE_SEL2")
		)
		(pad "W18" smd circle
			(at 5.199888 5.999988)
			(size 0.4064 0.4064)
			(layers "F.Cu" "F.Mask" "F.Paste")
			(net "RST_PEX_SSD6_PERST_R_N")
		)
		(pad "W19" smd circle
			(at 5.999988 5.999988)
			(size 0.4064 0.4064)
			(layers "F.Cu" "F.Mask" "F.Paste")
			(net "RST_FPGA_BIC_N")
		)
		(pad "W20" smd circle
			(at 6.800088 5.999988)
			(size 0.4064 0.4064)
			(layers "F.Cu" "F.Mask" "F.Paste")
			(net "PWRGD_PEX3_P1V8_PLL_R")
		)
		(pad "W21" smd circle
			(at 7.599934 5.999988)
			(size 0.4064 0.4064)
			(layers "F.Cu" "F.Mask" "F.Paste")
			(net "NIC4_PEX_PWR_EN_R")
		)
		(pad "W22" smd circle
			(at 8.400034 5.999988)
			(size 0.4064 0.4064)
			(layers "F.Cu" "F.Mask" "F.Paste")
			(net "PWRGD_PEX0_P1V8_PLL_R")
		)
		(pad "Y1" smd circle
			(at -8.400034 6.800088)
			(size 0.4064 0.4064)
			(layers "F.Cu" "F.Mask" "F.Paste")
			(net "RST_PEX_SSD12_PERST_R_N")
		)
		(pad "Y2" smd circle
			(at -7.599934 6.800088)
			(size 0.4064 0.4064)
			(layers "F.Cu" "F.Mask" "F.Paste")
			(net "GPU_3V3IO_RSVD1_ISO_R")
		)
		(pad "Y3" smd circle
			(at -6.800088 6.800088)
			(size 0.4064 0.4064)
			(layers "F.Cu" "F.Mask" "F.Paste")
			(net "SSD11_PWRDIS_BIC_R")
		)
		(pad "Y4" smd circle
			(at -5.999988 6.800088)
			(size 0.4064 0.4064)
			(layers "F.Cu" "F.Mask" "F.Paste")
			(net "SSD8_CLK_EN_N")
		)
		(pad "Y5" smd circle
			(at -5.199888 6.800088)
			(size 0.4064 0.4064)
			(layers "F.Cu" "F.Mask" "F.Paste")
			(net "PRSNT_SSD10_R_N")
		)
		(pad "Y6" smd circle
			(at -4.400042 6.800088)
			(size 0.4064 0.4064)
			(layers "F.Cu" "F.Mask" "F.Paste")
			(net "PWRGD_P12V_SSD10_R")
		)
		(pad "Y7" smd circle
			(at -3.599942 6.800088)
			(size 0.4064 0.4064)
			(layers "F.Cu" "F.Mask" "F.Paste")
			(net "GND")
		)
		(pad "Y8" smd circle
			(at -2.800096 6.800088)
			(size 0.4064 0.4064)
			(layers "F.Cu" "F.Mask" "F.Paste")
			(net "PWRGD_P3V3_SSD12_R")
		)
		(pad "Y9" smd circle
			(at -1.999996 6.800088)
			(size 0.4064 0.4064)
			(layers "F.Cu" "F.Mask" "F.Paste")
			(net "SSD13_PWR_EN")
		)
		(pad "Y10" smd circle
			(at -1.199896 6.800088)
			(size 0.4064 0.4064)
			(layers "F.Cu" "F.Mask" "F.Paste")
			(net "SSD13_PWRDIS")
		)
		(pad "Y11" smd circle
			(at -0.40005 6.800088)
			(size 0.4064 0.4064)
			(layers "F.Cu" "F.Mask" "F.Paste")
			(net "RST_SSD14_PERST_N")
		)
		(pad "Y12" smd circle
			(at 0.40005 6.800088)
			(size 0.4064 0.4064)
			(layers "F.Cu" "F.Mask" "F.Paste")
			(net "SSD14_CLK_EN_N")
		)
		(pad "Y13" smd circle
			(at 1.199896 6.800088)
			(size 0.4064 0.4064)
			(layers "F.Cu" "F.Mask" "F.Paste")
			(net "SSD15_CLK_EN_N")
		)
		(pad "Y14" smd circle
			(at 1.999996 6.800088)
			(size 0.4064 0.4064)
			(layers "F.Cu" "F.Mask" "F.Paste")
			(net "RST_PEX_SSD1_PERST_R_N")
		)
		(pad "Y15" smd circle
			(at 2.800096 6.800088)
			(size 0.4064 0.4064)
			(layers "F.Cu" "F.Mask" "F.Paste")
			(net "SSD2_PEX_PWR_EN_R")
		)
		(pad "Y16" smd circle
			(at 3.599942 6.800088)
			(size 0.4064 0.4064)
			(layers "F.Cu" "F.Mask" "F.Paste")
			(net "GND")
		)
		(pad "Y17" smd circle
			(at 4.400042 6.800088)
			(size 0.4064 0.4064)
			(layers "F.Cu" "F.Mask" "F.Paste")
			(net "FPGA_PEX1_MODE_SEL1")
		)
		(pad "Y18" smd circle
			(at 5.199888 6.800088)
			(size 0.4064 0.4064)
			(layers "F.Cu" "F.Mask" "F.Paste")
			(net "SSD4_PWRDIS_BIC_R")
		)
		(pad "Y19" smd circle
			(at 5.999988 6.800088)
			(size 0.4064 0.4064)
			(layers "F.Cu" "F.Mask" "F.Paste")
			(net "SSD6_PEX_PWR_EN_R")
		)
		(pad "Y20" smd circle
			(at 6.800088 6.800088)
			(size 0.4064 0.4064)
			(layers "F.Cu" "F.Mask" "F.Paste")
			(net "RST_FT4232_N")
		)
		(pad "Y21" smd circle
			(at 7.599934 6.800088)
			(size 0.4064 0.4064)
			(layers "F.Cu" "F.Mask" "F.Paste")
			(net "PRSNT_NIC5_FPGA_N")
		)
		(pad "Y22" smd circle
			(at 8.400034 6.800088)
			(size 0.4064 0.4064)
			(layers "F.Cu" "F.Mask" "F.Paste")
			(net "PRSNT_NIC4_FPGA_N")
		)
	)
)
